(kicad_pcb
	(version 20260206)
	(generator "pcbnew")
	(generator_version "10.0")
	(general
		(thickness 1.6)
		(legacy_teardrops no)
	)
	(paper "A4")
	(title_block
		(title "04192023_DAF0TMB3IC0_F0TG_MB_C_brd_V02_OCP.brd")
		(comment 1 "Grand Teton / footprint 2352 of 8354 (J1), pads 114-226 of 291")
	)
	(layers
		(0 "F.Cu" signal "TOP")
		(4 "In1.Cu" signal "GND")
		(6 "In2.Cu" signal "IN1")
		(8 "In3.Cu" signal "GND1")
		(10 "In4.Cu" signal "IN2")
		(12 "In5.Cu" signal "GND2")
		(14 "In6.Cu" signal "IN3")
		(16 "In7.Cu" signal "GND3")
		(18 "In8.Cu" signal "VCC")
		(20 "In9.Cu" signal "VCC1")
		(22 "In10.Cu" signal "GND4")
		(24 "In11.Cu" signal "IN4")
		(26 "In12.Cu" signal "GND5")
		(28 "In13.Cu" signal "IN5")
		(30 "In14.Cu" signal "GND6")
		(32 "In15.Cu" signal "IN6")
		(34 "In16.Cu" signal "GND7")
		(2 "B.Cu" signal "BOTTOM")
		(9 "F.Adhes" user "F.Adhesive")
		(11 "B.Adhes" user "B.Adhesive")
		(13 "F.Paste" user "Package Geometry/Pastemask Top")
		(15 "B.Paste" user "Package Geometry/Pastemask Bottom")
		(5 "F.SilkS" user "Ref Des/Silkscreen Top")
		(7 "B.SilkS" user "Ref Des/Silkscreen Bottom")
		(1 "F.Mask" user "Board Geometry/Soldermask Top")
		(3 "B.Mask" user "Board Geometry/Soldermask Bottom")
		(17 "Dwgs.User" user "User.Drawings")
		(19 "Cmts.User" user "User.Comments")
		(21 "Eco1.User" user "User.Eco1")
		(23 "Eco2.User" user "User.Eco2")
		(25 "Edge.Cuts" user "Board Geometry/Outline")
		(27 "Margin" user)
		(31 "F.CrtYd" user "Package Geometry/Place Bound Top")
		(29 "B.CrtYd" user "Package Geometry/Place Bound Bottom")
		(35 "F.Fab" user "Ref Des/Assembly Top")
		(33 "B.Fab" user "Ref Des/Assembly Bottom")
	)
	(footprint ""
		(layer "F.Cu")
		(at 305.31816 -255.560068 180)
		(property "Reference" "J1"
			(at -2.2098 -81.984088 0)
			(unlocked yes)
			(layer "F.SilkS")
			(effects
				(font
					(size 0.7874 0.5842)
					(thickness 0.1524)
				)
			)
		)
		(property "Value" ""
			(at 0 0 180)
			(layer "F.Fab")
			(effects
				(font
					(size 1.27 1.27)
				)
			)
		)
		(duplicate_pad_numbers_are_jumpers no)
		(pad "114" smd rect
			(at -2.050034 37.824918 90)
			(size 0.519938 1.4986)
			(layers "F.Cu" "F.Mask" "F.Paste")
			(net "GND")
		)
		(pad "115" smd rect
			(at -2.050034 38.675056 90)
			(size 0.519938 1.4986)
			(layers "F.Cu" "F.Mask" "F.Paste")
			(net "M_A_CPU0_SB_DQS_DP<1>")
		)
		(pad "116" smd rect
			(at -2.050034 39.52494 90)
			(size 0.519938 1.4986)
			(layers "F.Cu" "F.Mask" "F.Paste")
			(net "M_A_CPU0_SB_DQS_DN<1>")
		)
		(pad "117" smd rect
			(at -2.050034 40.375078 90)
			(size 0.519938 1.4986)
			(layers "F.Cu" "F.Mask" "F.Paste")
			(net "GND")
		)
		(pad "118" smd rect
			(at -2.050034 41.224962 90)
			(size 0.519938 1.4986)
			(layers "F.Cu" "F.Mask" "F.Paste")
			(net "M_A_CPU0_SB_DQ<12>")
		)
		(pad "119" smd rect
			(at -2.050034 42.0751 90)
			(size 0.519938 1.4986)
			(layers "F.Cu" "F.Mask" "F.Paste")
			(net "GND")
		)
		(pad "120" smd rect
			(at -2.050034 42.924984 90)
			(size 0.519938 1.4986)
			(layers "F.Cu" "F.Mask" "F.Paste")
			(net "M_A_CPU0_SB_DQ<13>")
		)
		(pad "121" smd rect
			(at -2.050034 43.775122 90)
			(size 0.519938 1.4986)
			(layers "F.Cu" "F.Mask" "F.Paste")
			(net "GND")
		)
		(pad "122" smd rect
			(at -2.050034 44.625006 90)
			(size 0.519938 1.4986)
			(layers "F.Cu" "F.Mask" "F.Paste")
			(net "M_A_CPU0_SB_DQ<16>")
		)
		(pad "123" smd rect
			(at -2.050034 45.47489 90)
			(size 0.519938 1.4986)
			(layers "F.Cu" "F.Mask" "F.Paste")
			(net "GND")
		)
		(pad "124" smd rect
			(at -2.050034 46.325028 90)
			(size 0.519938 1.4986)
			(layers "F.Cu" "F.Mask" "F.Paste")
			(net "M_A_CPU0_SB_DQ<17>")
		)
		(pad "125" smd rect
			(at -2.050034 47.174912 90)
			(size 0.519938 1.4986)
			(layers "F.Cu" "F.Mask" "F.Paste")
			(net "GND")
		)
		(pad "126" smd rect
			(at -2.050034 48.02505 90)
			(size 0.519938 1.4986)
			(layers "F.Cu" "F.Mask" "F.Paste")
			(net "M_A_CPU0_SB_DQS_DP<2>")
		)
		(pad "127" smd rect
			(at -2.050034 48.874934 90)
			(size 0.519938 1.4986)
			(layers "F.Cu" "F.Mask" "F.Paste")
			(net "M_A_CPU0_SB_DQS_DN<2>")
		)
		(pad "128" smd rect
			(at -2.050034 49.725072 90)
			(size 0.519938 1.4986)
			(layers "F.Cu" "F.Mask" "F.Paste")
			(net "GND")
		)
		(pad "129" smd rect
			(at -2.050034 50.574956 90)
			(size 0.519938 1.4986)
			(layers "F.Cu" "F.Mask" "F.Paste")
			(net "M_A_CPU0_SB_DQ<20>")
		)
		(pad "130" smd rect
			(at -2.050034 51.425094 90)
			(size 0.519938 1.4986)
			(layers "F.Cu" "F.Mask" "F.Paste")
			(net "GND")
		)
		(pad "131" smd rect
			(at -2.050034 52.274978 90)
			(size 0.519938 1.4986)
			(layers "F.Cu" "F.Mask" "F.Paste")
			(net "M_A_CPU0_SB_DQ<21>")
		)
		(pad "132" smd rect
			(at -2.050034 53.125116 90)
			(size 0.519938 1.4986)
			(layers "F.Cu" "F.Mask" "F.Paste")
			(net "GND")
		)
		(pad "133" smd rect
			(at -2.050034 53.975 90)
			(size 0.519938 1.4986)
			(layers "F.Cu" "F.Mask" "F.Paste")
			(net "M_A_CPU0_SB_DQ<24>")
		)
		(pad "134" smd rect
			(at -2.050034 54.824884 90)
			(size 0.519938 1.4986)
			(layers "F.Cu" "F.Mask" "F.Paste")
			(net "GND")
		)
		(pad "135" smd rect
			(at -2.050034 55.675022 90)
			(size 0.519938 1.4986)
			(layers "F.Cu" "F.Mask" "F.Paste")
			(net "M_A_CPU0_SB_DQ<25>")
		)
		(pad "136" smd rect
			(at -2.050034 56.524906 90)
			(size 0.519938 1.4986)
			(layers "F.Cu" "F.Mask" "F.Paste")
			(net "GND")
		)
		(pad "137" smd rect
			(at -2.050034 57.375044 90)
			(size 0.519938 1.4986)
			(layers "F.Cu" "F.Mask" "F.Paste")
			(net "M_A_CPU0_SB_DQS_DP<3>")
		)
		(pad "138" smd rect
			(at -2.050034 58.224928 90)
			(size 0.519938 1.4986)
			(layers "F.Cu" "F.Mask" "F.Paste")
			(net "M_A_CPU0_SB_DQS_DN<3>")
		)
		(pad "139" smd rect
			(at -2.050034 59.075066 90)
			(size 0.519938 1.4986)
			(layers "F.Cu" "F.Mask" "F.Paste")
			(net "GND")
		)
		(pad "140" smd rect
			(at -2.050034 59.92495 90)
			(size 0.519938 1.4986)
			(layers "F.Cu" "F.Mask" "F.Paste")
			(net "M_A_CPU0_SB_DQ<28>")
		)
		(pad "141" smd rect
			(at -2.050034 60.775088 90)
			(size 0.519938 1.4986)
			(layers "F.Cu" "F.Mask" "F.Paste")
			(net "GND")
		)
		(pad "142" smd rect
			(at -2.050034 61.624972 90)
			(size 0.519938 1.4986)
			(layers "F.Cu" "F.Mask" "F.Paste")
			(net "M_A_CPU0_SB_DQ<29>")
		)
		(pad "143" smd rect
			(at -2.050034 62.47511 90)
			(size 0.519938 1.4986)
			(layers "F.Cu" "F.Mask" "F.Paste")
			(net "GND")
		)
		(pad "144" smd rect
			(at -2.050034 63.324994 90)
			(size 0.519938 1.4986)
			(layers "F.Cu" "F.Mask" "F.Paste")
			(net "Net_2250")
		)
		(pad "145" smd rect
			(at 2.050034 -63.324994 90)
			(size 0.519938 1.4986)
			(layers "F.Cu" "F.Mask" "F.Paste")
			(net "P12V_MEM_CPU0")
		)
		(pad "146" smd rect
			(at 2.050034 -62.47511 90)
			(size 0.519938 1.4986)
			(layers "F.Cu" "F.Mask" "F.Paste")
			(net "P12V_MEM_CPU0")
		)
		(pad "147" smd rect
			(at 2.050034 -61.624972 90)
			(size 0.519938 1.4986)
			(layers "F.Cu" "F.Mask" "F.Paste")
			(net "PWRGD_CHA_CPU0_DIMM0")
		)
		(pad "148" smd rect
			(at 2.050034 -60.775088 90)
			(size 0.519938 1.4986)
			(layers "F.Cu" "F.Mask" "F.Paste")
			(net "PD_CHA_CPU0_DIMM0_SAA")
		)
		(pad "149" smd rect
			(at 2.050034 -59.92495 90)
			(size 0.519938 1.4986)
			(layers "F.Cu" "F.Mask" "F.Paste")
			(net "Net_2251")
		)
		(pad "150" smd rect
			(at 2.050034 -59.075066 90)
			(size 0.519938 1.4986)
			(layers "F.Cu" "F.Mask" "F.Paste")
			(net "Net_2252")
		)
		(pad "151" smd rect
			(at 2.050034 -58.224928 90)
			(size 0.519938 1.4986)
			(layers "F.Cu" "F.Mask" "F.Paste")
			(net "GND")
		)
		(pad "152" smd rect
			(at 2.050034 -57.375044 90)
			(size 0.519938 1.4986)
			(layers "F.Cu" "F.Mask" "F.Paste")
			(net "M_A_CPU0_SA_DQ<2>")
		)
		(pad "153" smd rect
			(at 2.050034 -56.524906 90)
			(size 0.519938 1.4986)
			(layers "F.Cu" "F.Mask" "F.Paste")
			(net "GND")
		)
		(pad "154" smd rect
			(at 2.050034 -55.675022 90)
			(size 0.519938 1.4986)
			(layers "F.Cu" "F.Mask" "F.Paste")
			(net "M_A_CPU0_SA_DQ<3>")
		)
		(pad "155" smd rect
			(at 2.050034 -54.824884 90)
			(size 0.519938 1.4986)
			(layers "F.Cu" "F.Mask" "F.Paste")
			(net "GND")
		)
		(pad "156" smd rect
			(at 2.050034 -53.975 90)
			(size 0.519938 1.4986)
			(layers "F.Cu" "F.Mask" "F.Paste")
			(net "M_A_CPU0_SA_DQS_DN<5>")
		)
		(pad "157" smd rect
			(at 2.050034 -53.125116 90)
			(size 0.519938 1.4986)
			(layers "F.Cu" "F.Mask" "F.Paste")
			(net "M_A_CPU0_SA_DQS_DP<5>")
		)
		(pad "158" smd rect
			(at 2.050034 -52.274978 90)
			(size 0.519938 1.4986)
			(layers "F.Cu" "F.Mask" "F.Paste")
			(net "GND")
		)
		(pad "159" smd rect
			(at 2.050034 -51.425094 90)
			(size 0.519938 1.4986)
			(layers "F.Cu" "F.Mask" "F.Paste")
			(net "M_A_CPU0_SA_DQ<6>")
		)
		(pad "160" smd rect
			(at 2.050034 -50.574956 90)
			(size 0.519938 1.4986)
			(layers "F.Cu" "F.Mask" "F.Paste")
			(net "GND")
		)
		(pad "161" smd rect
			(at 2.050034 -49.725072 90)
			(size 0.519938 1.4986)
			(layers "F.Cu" "F.Mask" "F.Paste")
			(net "M_A_CPU0_SA_DQ<7>")
		)
		(pad "162" smd rect
			(at 2.050034 -48.874934 90)
			(size 0.519938 1.4986)
			(layers "F.Cu" "F.Mask" "F.Paste")
			(net "GND")
		)
		(pad "163" smd rect
			(at 2.050034 -48.02505 90)
			(size 0.519938 1.4986)
			(layers "F.Cu" "F.Mask" "F.Paste")
			(net "M_A_CPU0_SA_DQ<10>")
		)
		(pad "164" smd rect
			(at 2.050034 -47.174912 90)
			(size 0.519938 1.4986)
			(layers "F.Cu" "F.Mask" "F.Paste")
			(net "GND")
		)
		(pad "165" smd rect
			(at 2.050034 -46.325028 90)
			(size 0.519938 1.4986)
			(layers "F.Cu" "F.Mask" "F.Paste")
			(net "M_A_CPU0_SA_DQ<11>")
		)
		(pad "166" smd rect
			(at 2.050034 -45.47489 90)
			(size 0.519938 1.4986)
			(layers "F.Cu" "F.Mask" "F.Paste")
			(net "GND")
		)
		(pad "167" smd rect
			(at 2.050034 -44.625006 90)
			(size 0.519938 1.4986)
			(layers "F.Cu" "F.Mask" "F.Paste")
			(net "M_A_CPU0_SA_DQS_DN<6>")
		)
		(pad "168" smd rect
			(at 2.050034 -43.775122 90)
			(size 0.519938 1.4986)
			(layers "F.Cu" "F.Mask" "F.Paste")
			(net "M_A_CPU0_SA_DQS_DP<6>")
		)
		(pad "169" smd rect
			(at 2.050034 -42.924984 90)
			(size 0.519938 1.4986)
			(layers "F.Cu" "F.Mask" "F.Paste")
			(net "GND")
		)
		(pad "170" smd rect
			(at 2.050034 -42.0751 90)
			(size 0.519938 1.4986)
			(layers "F.Cu" "F.Mask" "F.Paste")
			(net "M_A_CPU0_SA_DQ<14>")
		)
		(pad "171" smd rect
			(at 2.050034 -41.224962 90)
			(size 0.519938 1.4986)
			(layers "F.Cu" "F.Mask" "F.Paste")
			(net "GND")
		)
		(pad "172" smd rect
			(at 2.050034 -40.375078 90)
			(size 0.519938 1.4986)
			(layers "F.Cu" "F.Mask" "F.Paste")
			(net "M_A_CPU0_SA_DQ<15>")
		)
		(pad "173" smd rect
			(at 2.050034 -39.52494 90)
			(size 0.519938 1.4986)
			(layers "F.Cu" "F.Mask" "F.Paste")
			(net "GND")
		)
		(pad "174" smd rect
			(at 2.050034 -38.675056 90)
			(size 0.519938 1.4986)
			(layers "F.Cu" "F.Mask" "F.Paste")
			(net "M_A_CPU0_SA_DQ<18>")
		)
		(pad "175" smd rect
			(at 2.050034 -37.824918 90)
			(size 0.519938 1.4986)
			(layers "F.Cu" "F.Mask" "F.Paste")
			(net "GND")
		)
		(pad "176" smd rect
			(at 2.050034 -36.975034 90)
			(size 0.519938 1.4986)
			(layers "F.Cu" "F.Mask" "F.Paste")
			(net "M_A_CPU0_SA_DQ<19>")
		)
		(pad "177" smd rect
			(at 2.050034 -36.124896 90)
			(size 0.519938 1.4986)
			(layers "F.Cu" "F.Mask" "F.Paste")
			(net "GND")
		)
		(pad "178" smd rect
			(at 2.050034 -35.275012 90)
			(size 0.519938 1.4986)
			(layers "F.Cu" "F.Mask" "F.Paste")
			(net "M_A_CPU0_SA_DQS_DN<7>")
		)
		(pad "179" smd rect
			(at 2.050034 -34.425128 90)
			(size 0.519938 1.4986)
			(layers "F.Cu" "F.Mask" "F.Paste")
			(net "M_A_CPU0_SA_DQS_DP<7>")
		)
		(pad "180" smd rect
			(at 2.050034 -33.57499 90)
			(size 0.519938 1.4986)
			(layers "F.Cu" "F.Mask" "F.Paste")
			(net "GND")
		)
		(pad "181" smd rect
			(at 2.050034 -32.725106 90)
			(size 0.519938 1.4986)
			(layers "F.Cu" "F.Mask" "F.Paste")
			(net "M_A_CPU0_SA_DQ<22>")
		)
		(pad "182" smd rect
			(at 2.050034 -31.874968 90)
			(size 0.519938 1.4986)
			(layers "F.Cu" "F.Mask" "F.Paste")
			(net "GND")
		)
		(pad "183" smd rect
			(at 2.050034 -31.025084 90)
			(size 0.519938 1.4986)
			(layers "F.Cu" "F.Mask" "F.Paste")
			(net "M_A_CPU0_SA_DQ<23>")
		)
		(pad "184" smd rect
			(at 2.050034 -30.174946 90)
			(size 0.519938 1.4986)
			(layers "F.Cu" "F.Mask" "F.Paste")
			(net "GND")
		)
		(pad "185" smd rect
			(at 2.050034 -29.325062 90)
			(size 0.519938 1.4986)
			(layers "F.Cu" "F.Mask" "F.Paste")
			(net "M_A_CPU0_SA_DQ<26>")
		)
		(pad "186" smd rect
			(at 2.050034 -28.474924 90)
			(size 0.519938 1.4986)
			(layers "F.Cu" "F.Mask" "F.Paste")
			(net "GND")
		)
		(pad "187" smd rect
			(at 2.050034 -27.62504 90)
			(size 0.519938 1.4986)
			(layers "F.Cu" "F.Mask" "F.Paste")
			(net "M_A_CPU0_SA_DQ<27>")
		)
		(pad "188" smd rect
			(at 2.050034 -26.774902 90)
			(size 0.519938 1.4986)
			(layers "F.Cu" "F.Mask" "F.Paste")
			(net "GND")
		)
		(pad "189" smd rect
			(at 2.050034 -25.925018 90)
			(size 0.519938 1.4986)
			(layers "F.Cu" "F.Mask" "F.Paste")
			(net "M_A_CPU0_SA_DQS_DN<8>")
		)
		(pad "190" smd rect
			(at 2.050034 -25.07488 90)
			(size 0.519938 1.4986)
			(layers "F.Cu" "F.Mask" "F.Paste")
			(net "M_A_CPU0_SA_DQS_DP<8>")
		)
		(pad "191" smd rect
			(at 2.050034 -24.224996 90)
			(size 0.519938 1.4986)
			(layers "F.Cu" "F.Mask" "F.Paste")
			(net "GND")
		)
		(pad "192" smd rect
			(at 2.050034 -23.375112 90)
			(size 0.519938 1.4986)
			(layers "F.Cu" "F.Mask" "F.Paste")
			(net "M_A_CPU0_SA_DQ<30>")
		)
		(pad "193" smd rect
			(at 2.050034 -22.524974 90)
			(size 0.519938 1.4986)
			(layers "F.Cu" "F.Mask" "F.Paste")
			(net "GND")
		)
		(pad "194" smd rect
			(at 2.050034 -21.67509 90)
			(size 0.519938 1.4986)
			(layers "F.Cu" "F.Mask" "F.Paste")
			(net "M_A_CPU0_SA_DQ<31>")
		)
		(pad "195" smd rect
			(at 2.050034 -20.824952 90)
			(size 0.519938 1.4986)
			(layers "F.Cu" "F.Mask" "F.Paste")
			(net "GND")
		)
		(pad "196" smd rect
			(at 2.050034 -19.975068 90)
			(size 0.519938 1.4986)
			(layers "F.Cu" "F.Mask" "F.Paste")
			(net "M_A_CPU0_SA_CB<2>")
		)
		(pad "197" smd rect
			(at 2.050034 -19.12493 90)
			(size 0.519938 1.4986)
			(layers "F.Cu" "F.Mask" "F.Paste")
			(net "GND")
		)
		(pad "198" smd rect
			(at 2.050034 -18.275046 90)
			(size 0.519938 1.4986)
			(layers "F.Cu" "F.Mask" "F.Paste")
			(net "M_A_CPU0_SA_CB<3>")
		)
		(pad "199" smd rect
			(at 2.050034 -17.424908 90)
			(size 0.519938 1.4986)
			(layers "F.Cu" "F.Mask" "F.Paste")
			(net "GND")
		)
		(pad "200" smd rect
			(at 2.050034 -16.575024 90)
			(size 0.519938 1.4986)
			(layers "F.Cu" "F.Mask" "F.Paste")
			(net "M_A_CPU0_SA_DQS_DN<9>")
		)
		(pad "201" smd rect
			(at 2.050034 -15.724886 90)
			(size 0.519938 1.4986)
			(layers "F.Cu" "F.Mask" "F.Paste")
			(net "M_A_CPU0_SA_DQS_DP<9>")
		)
		(pad "202" smd rect
			(at 2.050034 -14.875002 90)
			(size 0.519938 1.4986)
			(layers "F.Cu" "F.Mask" "F.Paste")
			(net "GND")
		)
		(pad "203" smd rect
			(at 2.050034 -14.025118 90)
			(size 0.519938 1.4986)
			(layers "F.Cu" "F.Mask" "F.Paste")
			(net "M_A_CPU0_SA_CB<6>")
		)
		(pad "204" smd rect
			(at 2.050034 -13.17498 90)
			(size 0.519938 1.4986)
			(layers "F.Cu" "F.Mask" "F.Paste")
			(net "GND")
		)
		(pad "205" smd rect
			(at 2.050034 -12.325096 90)
			(size 0.519938 1.4986)
			(layers "F.Cu" "F.Mask" "F.Paste")
			(net "M_A_CPU0_SA_CB<7>")
		)
		(pad "206" smd rect
			(at 2.050034 -11.474958 90)
			(size 0.519938 1.4986)
			(layers "F.Cu" "F.Mask" "F.Paste")
			(net "GND")
		)
		(pad "207" smd rect
			(at 2.050034 -10.625074 90)
			(size 0.519938 1.4986)
			(layers "F.Cu" "F.Mask" "F.Paste")
			(net "M_A_CPU0_RESET_N")
		)
		(pad "208" smd rect
			(at 2.050034 -9.774936 90)
			(size 0.519938 1.4986)
			(layers "F.Cu" "F.Mask" "F.Paste")
			(net "GND")
		)
		(pad "209" smd rect
			(at 2.050034 -8.925052 90)
			(size 0.519938 1.4986)
			(layers "F.Cu" "F.Mask" "F.Paste")
			(net "M_A_CPU0_SA_CS_N<1>")
		)
		(pad "210" smd rect
			(at 2.050034 -8.074914 90)
			(size 0.519938 1.4986)
			(layers "F.Cu" "F.Mask" "F.Paste")
			(net "GND")
		)
		(pad "211" smd rect
			(at 2.050034 -7.22503 90)
			(size 0.519938 1.4986)
			(layers "F.Cu" "F.Mask" "F.Paste")
			(net "M_A_CPU0_SA_CA<1>")
		)
		(pad "212" smd rect
			(at 2.050034 -6.374892 90)
			(size 0.519938 1.4986)
			(layers "F.Cu" "F.Mask" "F.Paste")
			(net "GND")
		)
		(pad "213" smd rect
			(at 2.050034 -5.525008 90)
			(size 0.519938 1.4986)
			(layers "F.Cu" "F.Mask" "F.Paste")
			(net "M_A_CPU0_SA_CA<3>")
		)
		(pad "214" smd rect
			(at 2.050034 -4.675124 90)
			(size 0.519938 1.4986)
			(layers "F.Cu" "F.Mask" "F.Paste")
			(net "GND")
		)
		(pad "215" smd rect
			(at 2.050034 -3.824986 90)
			(size 0.519938 1.4986)
			(layers "F.Cu" "F.Mask" "F.Paste")
			(net "M_A_CPU0_SA_CA<5>")
		)
		(pad "216" smd rect
			(at 2.050034 -2.975102 90)
			(size 0.519938 1.4986)
			(layers "F.Cu" "F.Mask" "F.Paste")
			(net "GND")
		)
		(pad "217" smd rect
			(at 2.050034 -2.124964 90)
			(size 0.519938 1.4986)
			(layers "F.Cu" "F.Mask" "F.Paste")
			(net "M_A_CPU0_CLK_DP<0>")
		)
		(pad "218" smd rect
			(at 2.050034 -1.27508 90)
			(size 0.519938 1.4986)
			(layers "F.Cu" "F.Mask" "F.Paste")
			(net "M_A_CPU0_CLK_DN<0>")
		)
		(pad "219" smd rect
			(at 2.050034 -0.424942 90)
			(size 0.519938 1.4986)
			(layers "F.Cu" "F.Mask" "F.Paste")
			(net "GND")
		)
		(pad "220" smd rect
			(at 2.050034 5.525008 90)
			(size 0.519938 1.4986)
			(layers "F.Cu" "F.Mask" "F.Paste")
			(net "Net_2253")
		)
		(pad "221" smd rect
			(at 2.050034 6.374892 90)
			(size 0.519938 1.4986)
			(layers "F.Cu" "F.Mask" "F.Paste")
			(net "M_A_CPU0_SB_CA<1>")
		)
		(pad "222" smd rect
			(at 2.050034 7.22503 90)
			(size 0.519938 1.4986)
			(layers "F.Cu" "F.Mask" "F.Paste")
			(net "GND")
		)
		(pad "223" smd rect
			(at 2.050034 8.074914 90)
			(size 0.519938 1.4986)
			(layers "F.Cu" "F.Mask" "F.Paste")
			(net "M_A_CPU0_SB_CA<3>")
		)
		(pad "224" smd rect
			(at 2.050034 8.925052 90)
			(size 0.519938 1.4986)
			(layers "F.Cu" "F.Mask" "F.Paste")
			(net "GND")
		)
		(pad "225" smd rect
			(at 2.050034 9.774936 90)
			(size 0.519938 1.4986)
			(layers "F.Cu" "F.Mask" "F.Paste")
			(net "M_A_CPU0_SB_CA<5>")
		)
		(pad "226" smd rect
			(at 2.050034 10.625074 90)
			(size 0.519938 1.4986)
			(layers "F.Cu" "F.Mask" "F.Paste")
			(net "GND")
		)
	)
)
